(kicad_pcb
	(version 20260206)
	(generator "pcbnew")
	(generator_version "10.0")
	(general
		(thickness 1.6)
		(legacy_teardrops no)
	)
	(paper "A4")
	(title_block
		(title "01162023_DA0F0TEBIF0_F0T_Expander_BD_F_brd_V02_OCP.brd")
		(comment 1 "Grand Teton / footprints 9501-9507 of 9728")
	)
	(layers
		(0 "F.Cu" signal "TOP")
		(4 "In1.Cu" signal "GND")
		(6 "In2.Cu" signal "VCC")
		(8 "In3.Cu" signal "VCC1")
		(10 "In4.Cu" signal "GND1")
		(12 "In5.Cu" signal "IN1")
		(14 "In6.Cu" signal "GND2")
		(16 "In7.Cu" signal "IN2")
		(18 "In8.Cu" signal "GND3")
		(20 "In9.Cu" signal "IN3")
		(22 "In10.Cu" signal "GND4")
		(24 "In11.Cu" signal "IN4")
		(26 "In12.Cu" signal "GND5")
		(28 "In13.Cu" signal "IN5")
		(30 "In14.Cu" signal "GND6")
		(32 "In15.Cu" signal "IN6")
		(34 "In16.Cu" signal "GND7")
		(2 "B.Cu" signal "BOTTOM")
		(9 "F.Adhes" user "F.Adhesive")
		(11 "B.Adhes" user "B.Adhesive")
		(13 "F.Paste" user "Package Geometry/Pastemask Top")
		(15 "B.Paste" user "Package Geometry/Pastemask Bottom")
		(5 "F.SilkS" user "Ref Des/Silkscreen Top")
		(7 "B.SilkS" user "Ref Des/Silkscreen Bottom")
		(1 "F.Mask" user "Board Geometry/Soldermask Top")
		(3 "B.Mask" user "Board Geometry/Soldermask Bottom")
		(17 "Dwgs.User" user "User.Drawings")
		(19 "Cmts.User" user "User.Comments")
		(21 "Eco1.User" user "User.Eco1")
		(23 "Eco2.User" user "User.Eco2")
		(25 "Edge.Cuts" user "Board Geometry/Outline")
		(27 "Margin" user)
		(31 "F.CrtYd" user "Package Geometry/Place Bound Top")
		(29 "B.CrtYd" user "Package Geometry/Place Bound Bottom")
		(35 "F.Fab" user "Ref Des/Assembly Top")
		(33 "B.Fab" user "Ref Des/Assembly Bottom")
	)
	(footprint ""
		(layer "B.Cu")
		(at 114.833654 -282.251404 180)
		(property "Reference" "PR7166"
			(at 0 0 0)
			(layer "B.SilkS")
			(hide yes)
			(effects
				(font
					(size 1.27 1.27)
				)
				(justify mirror)
			)
		)
		(property "Value" ""
			(at 0 0 0)
			(layer "B.Fab")
			(effects
				(font
					(size 1.27 1.27)
				)
				(justify mirror)
			)
		)
		(duplicate_pad_numbers_are_jumpers no)
		(fp_line
			(start 0.7874 0.4064)
			(end 0.7874 -0.4064)
			(stroke
				(width 0.1524)
				(type default)
			)
			(layer "B.SilkS")
		)
		(fp_line
			(start 0.7874 -0.4064)
			(end -0.7874 -0.4064)
			(stroke
				(width 0.1524)
				(type default)
			)
			(layer "B.SilkS")
		)
		(fp_line
			(start -0.7874 0.4064)
			(end 0.7874 0.4064)
			(stroke
				(width 0.1524)
				(type default)
			)
			(layer "B.SilkS")
		)
		(fp_line
			(start -0.7874 -0.4064)
			(end -0.7874 0.4064)
			(stroke
				(width 0.1524)
				(type default)
			)
			(layer "B.SilkS")
		)
		(fp_line
			(start 0.67945 0.3048)
			(end 0.67945 -0.305054)
			(stroke
				(width 0.1)
				(type default)
			)
			(layer "B.Fab")
		)
		(fp_line
			(start 0.67945 -0.305054)
			(end 0.12065 -0.305054)
			(stroke
				(width 0.1)
				(type default)
			)
			(layer "B.Fab")
		)
		(fp_line
			(start 0.12065 0.3048)
			(end 0.67945 0.3048)
			(stroke
				(width 0.1)
				(type default)
			)
			(layer "B.Fab")
		)
		(fp_line
			(start 0.12065 0.2794)
			(end 0.12065 0.3048)
			(stroke
				(width 0.1)
				(type default)
			)
			(layer "B.Fab")
		)
		(fp_line
			(start 0.12065 -0.2794)
			(end -0.12065 -0.2794)
			(stroke
				(width 0.1)
				(type default)
			)
			(layer "B.Fab")
		)
		(fp_line
			(start 0.12065 -0.305054)
			(end 0.12065 -0.2794)
			(stroke
				(width 0.1)
				(type default)
			)
			(layer "B.Fab")
		)
		(fp_line
			(start -0.120396 0.3048)
			(end -0.120396 0.2794)
			(stroke
				(width 0.1)
				(type default)
			)
			(layer "B.Fab")
		)
		(fp_line
			(start -0.120396 0.2794)
			(end 0.12065 0.2794)
			(stroke
				(width 0.1)
				(type default)
			)
			(layer "B.Fab")
		)
		(fp_line
			(start -0.12065 -0.2794)
			(end -0.12065 -0.3048)
			(stroke
				(width 0.1)
				(type default)
			)
			(layer "B.Fab")
		)
		(fp_line
			(start -0.12065 -0.3048)
			(end -0.67945 -0.3048)
			(stroke
				(width 0.1)
				(type default)
			)
			(layer "B.Fab")
		)
		(fp_line
			(start -0.67945 0.3048)
			(end -0.120396 0.3048)
			(stroke
				(width 0.1)
				(type default)
			)
			(layer "B.Fab")
		)
		(fp_line
			(start -0.67945 -0.3048)
			(end -0.67945 0.3048)
			(stroke
				(width 0.1)
				(type default)
			)
			(layer "B.Fab")
		)
		(pad "1" smd circle
			(at 0.40005 0)
			(size 0 0)
			(layers "B.Cu" "B.Mask" "B.Paste")
			(net "P0V8_PEX0_EN2")
		)
		(pad "2" smd circle
			(at -0.40005 0)
			(size 0 0)
			(layers "B.Cu" "B.Mask" "B.Paste")
			(net "P0V8_PEX0_VCC2")
		)
	)
	(footprint ""
		(layer "B.Cu")
		(at 232.0671 -91.588082 180)
		(property "Reference" "C2616"
			(at 0 0 0)
			(layer "B.SilkS")
			(hide yes)
			(effects
				(font
					(size 1.27 1.27)
				)
				(justify mirror)
			)
		)
		(property "Value" ""
			(at 0 0 0)
			(layer "B.Fab")
			(effects
				(font
					(size 1.27 1.27)
				)
				(justify mirror)
			)
		)
		(duplicate_pad_numbers_are_jumpers no)
		(fp_line
			(start 0.7874 0.4064)
			(end 0.7874 -0.4064)
			(stroke
				(width 0.1524)
				(type default)
			)
			(layer "B.SilkS")
		)
		(fp_line
			(start 0.7874 -0.4064)
			(end -0.7874 -0.4064)
			(stroke
				(width 0.1524)
				(type default)
			)
			(layer "B.SilkS")
		)
		(fp_line
			(start -0.7874 0.4064)
			(end 0.7874 0.4064)
			(stroke
				(width 0.1524)
				(type default)
			)
			(layer "B.SilkS")
		)
		(fp_line
			(start -0.7874 -0.4064)
			(end -0.7874 0.4064)
			(stroke
				(width 0.1524)
				(type default)
			)
			(layer "B.SilkS")
		)
		(fp_line
			(start 0.67945 0.3048)
			(end 0.67945 -0.305054)
			(stroke
				(width 0.1)
				(type default)
			)
			(layer "B.Fab")
		)
		(fp_line
			(start 0.67945 -0.305054)
			(end 0.12065 -0.305054)
			(stroke
				(width 0.1)
				(type default)
			)
			(layer "B.Fab")
		)
		(fp_line
			(start 0.12065 0.3048)
			(end 0.67945 0.3048)
			(stroke
				(width 0.1)
				(type default)
			)
			(layer "B.Fab")
		)
		(fp_line
			(start 0.12065 0.2794)
			(end 0.12065 0.3048)
			(stroke
				(width 0.1)
				(type default)
			)
			(layer "B.Fab")
		)
		(fp_line
			(start 0.12065 -0.2794)
			(end -0.12065 -0.2794)
			(stroke
				(width 0.1)
				(type default)
			)
			(layer "B.Fab")
		)
		(fp_line
			(start 0.12065 -0.305054)
			(end 0.12065 -0.2794)
			(stroke
				(width 0.1)
				(type default)
			)
			(layer "B.Fab")
		)
		(fp_line
			(start -0.120396 0.3048)
			(end -0.120396 0.2794)
			(stroke
				(width 0.1)
				(type default)
			)
			(layer "B.Fab")
		)
		(fp_line
			(start -0.120396 0.2794)
			(end 0.12065 0.2794)
			(stroke
				(width 0.1)
				(type default)
			)
			(layer "B.Fab")
		)
		(fp_line
			(start -0.12065 -0.2794)
			(end -0.12065 -0.3048)
			(stroke
				(width 0.1)
				(type default)
			)
			(layer "B.Fab")
		)
		(fp_line
			(start -0.12065 -0.3048)
			(end -0.67945 -0.3048)
			(stroke
				(width 0.1)
				(type default)
			)
			(layer "B.Fab")
		)
		(fp_line
			(start -0.67945 0.3048)
			(end -0.120396 0.3048)
			(stroke
				(width 0.1)
				(type default)
			)
			(layer "B.Fab")
		)
		(fp_line
			(start -0.67945 -0.3048)
			(end -0.67945 0.3048)
			(stroke
				(width 0.1)
				(type default)
			)
			(layer "B.Fab")
		)
		(pad "1" smd circle
			(at 0.40005 0)
			(size 0 0)
			(layers "B.Cu" "B.Mask" "B.Paste")
			(net "P3V3_PEX_USB_HUB")
		)
		(pad "2" smd circle
			(at -0.40005 0)
			(size 0 0)
			(layers "B.Cu" "B.Mask" "B.Paste")
			(net "GND")
		)
	)
	(footprint ""
		(layer "B.Cu")
		(at 402.249894 -290.199826 90)
		(property "Reference" "C1968"
			(at 0 0 90)
			(layer "B.SilkS")
			(hide yes)
			(effects
				(font
					(size 1.27 1.27)
				)
				(justify mirror)
			)
		)
		(property "Value" ""
			(at 0 0 90)
			(layer "B.Fab")
			(effects
				(font
					(size 1.27 1.27)
				)
				(justify mirror)
			)
		)
		(duplicate_pad_numbers_are_jumpers no)
		(fp_line
			(start 0.299974 -0.150114)
			(end -0.299974 -0.150114)
			(stroke
				(width 0.1)
				(type default)
			)
			(layer "B.Fab")
		)
		(fp_line
			(start -0.299974 -0.150114)
			(end -0.299974 0.150114)
			(stroke
				(width 0.1)
				(type default)
			)
			(layer "B.Fab")
		)
		(fp_line
			(start 0.299974 0.150114)
			(end 0.299974 -0.150114)
			(stroke
				(width 0.1)
				(type default)
			)
			(layer "B.Fab")
		)
		(fp_line
			(start -0.299974 0.150114)
			(end 0.299974 0.150114)
			(stroke
				(width 0.1)
				(type default)
			)
			(layer "B.Fab")
		)
		(pad "1" smd rect
			(at 0.2667 0 270)
			(size 0.3048 0.381)
			(layers "B.Cu" "B.Mask" "B.Paste")
			(net "P0V8_SERDES_VDDA_PEX3")
		)
		(pad "2" smd rect
			(at -0.2667 0 270)
			(size 0.3048 0.381)
			(layers "B.Cu" "B.Mask" "B.Paste")
			(net "GND")
		)
	)
	(footprint ""
		(layer "B.Cu")
		(at 213.106 -198.755 -90)
		(property "Reference" "R6310"
			(at 0 0 90)
			(layer "B.SilkS")
			(hide yes)
			(effects
				(font
					(size 1.27 1.27)
				)
				(justify mirror)
			)
		)
		(property "Value" ""
			(at 0 0 90)
			(layer "B.Fab")
			(effects
				(font
					(size 1.27 1.27)
				)
				(justify mirror)
			)
		)
		(duplicate_pad_numbers_are_jumpers no)
		(fp_line
			(start -0.7874 0.4064)
			(end 0.7874 0.4064)
			(stroke
				(width 0.1524)
				(type default)
			)
			(layer "B.SilkS")
		)
		(fp_line
			(start 0.7874 0.4064)
			(end 0.7874 -0.4064)
			(stroke
				(width 0.1524)
				(type default)
			)
			(layer "B.SilkS")
		)
		(fp_line
			(start -0.7874 -0.4064)
			(end -0.7874 0.4064)
			(stroke
				(width 0.1524)
				(type default)
			)
			(layer "B.SilkS")
		)
		(fp_line
			(start 0.7874 -0.4064)
			(end -0.7874 -0.4064)
			(stroke
				(width 0.1524)
				(type default)
			)
			(layer "B.SilkS")
		)
		(fp_line
			(start -0.67945 0.3048)
			(end -0.120396 0.3048)
			(stroke
				(width 0.1)
				(type default)
			)
			(layer "B.Fab")
		)
		(fp_line
			(start -0.120396 0.3048)
			(end -0.120396 0.2794)
			(stroke
				(width 0.1)
				(type default)
			)
			(layer "B.Fab")
		)
		(fp_line
			(start 0.12065 0.3048)
			(end 0.67945 0.3048)
			(stroke
				(width 0.1)
				(type default)
			)
			(layer "B.Fab")
		)
		(fp_line
			(start 0.67945 0.3048)
			(end 0.67945 -0.305054)
			(stroke
				(width 0.1)
				(type default)
			)
			(layer "B.Fab")
		)
		(fp_line
			(start -0.120396 0.2794)
			(end 0.12065 0.2794)
			(stroke
				(width 0.1)
				(type default)
			)
			(layer "B.Fab")
		)
		(fp_line
			(start 0.12065 0.2794)
			(end 0.12065 0.3048)
			(stroke
				(width 0.1)
				(type default)
			)
			(layer "B.Fab")
		)
		(fp_line
			(start -0.12065 -0.2794)
			(end -0.12065 -0.3048)
			(stroke
				(width 0.1)
				(type default)
			)
			(layer "B.Fab")
		)
		(fp_line
			(start 0.12065 -0.2794)
			(end -0.12065 -0.2794)
			(stroke
				(width 0.1)
				(type default)
			)
			(layer "B.Fab")
		)
		(fp_line
			(start -0.67945 -0.3048)
			(end -0.67945 0.3048)
			(stroke
				(width 0.1)
				(type default)
			)
			(layer "B.Fab")
		)
		(fp_line
			(start -0.12065 -0.3048)
			(end -0.67945 -0.3048)
			(stroke
				(width 0.1)
				(type default)
			)
			(layer "B.Fab")
		)
		(fp_line
			(start 0.12065 -0.305054)
			(end 0.12065 -0.2794)
			(stroke
				(width 0.1)
				(type default)
			)
			(layer "B.Fab")
		)
		(fp_line
			(start 0.67945 -0.305054)
			(end 0.12065 -0.305054)
			(stroke
				(width 0.1)
				(type default)
			)
			(layer "B.Fab")
		)
		(pad "1" smd circle
			(at 0.40005 0 90)
			(size 0 0)
			(layers "B.Cu" "B.Mask" "B.Paste")
			(net "SMB_NIC6_LS_SDA")
		)
		(pad "2" smd circle
			(at -0.40005 0 90)
			(size 0 0)
			(layers "B.Cu" "B.Mask" "B.Paste")
			(net "SMB_NIC6_LS_R_SDA")
		)
	)
	(footprint ""
		(layer "B.Cu")
		(at 235.921296 -93.120718)
		(property "Reference" "C2621"
			(at 0 0 0)
			(layer "B.SilkS")
			(hide yes)
			(effects
				(font
					(size 1.27 1.27)
				)
				(justify mirror)
			)
		)
		(property "Value" ""
			(at 0 0 0)
			(layer "B.Fab")
			(effects
				(font
					(size 1.27 1.27)
				)
				(justify mirror)
			)
		)
		(duplicate_pad_numbers_are_jumpers no)
		(fp_line
			(start -0.7874 -0.4064)
			(end -0.7874 0.4064)
			(stroke
				(width 0.1524)
				(type default)
			)
			(layer "B.SilkS")
		)
		(fp_line
			(start -0.7874 0.4064)
			(end 0.7874 0.4064)
			(stroke
				(width 0.1524)
				(type default)
			)
			(layer "B.SilkS")
		)
		(fp_line
			(start 0.7874 -0.4064)
			(end -0.7874 -0.4064)
			(stroke
				(width 0.1524)
				(type default)
			)
			(layer "B.SilkS")
		)
		(fp_line
			(start 0.7874 0.4064)
			(end 0.7874 -0.4064)
			(stroke
				(width 0.1524)
				(type default)
			)
			(layer "B.SilkS")
		)
		(fp_line
			(start -0.67945 -0.3048)
			(end -0.67945 0.3048)
			(stroke
				(width 0.1)
				(type default)
			)
			(layer "B.Fab")
		)
		(fp_line
			(start -0.67945 0.3048)
			(end -0.120396 0.3048)
			(stroke
				(width 0.1)
				(type default)
			)
			(layer "B.Fab")
		)
		(fp_line
			(start -0.12065 -0.3048)
			(end -0.67945 -0.3048)
			(stroke
				(width 0.1)
				(type default)
			)
			(layer "B.Fab")
		)
		(fp_line
			(start -0.12065 -0.2794)
			(end -0.12065 -0.3048)
			(stroke
				(width 0.1)
				(type default)
			)
			(layer "B.Fab")
		)
		(fp_line
			(start -0.120396 0.2794)
			(end 0.12065 0.2794)
			(stroke
				(width 0.1)
				(type default)
			)
			(layer "B.Fab")
		)
		(fp_line
			(start -0.120396 0.3048)
			(end -0.120396 0.2794)
			(stroke
				(width 0.1)
				(type default)
			)
			(layer "B.Fab")
		)
		(fp_line
			(start 0.12065 -0.305054)
			(end 0.12065 -0.2794)
			(stroke
				(width 0.1)
				(type default)
			)
			(layer "B.Fab")
		)
		(fp_line
			(start 0.12065 -0.2794)
			(end -0.12065 -0.2794)
			(stroke
				(width 0.1)
				(type default)
			)
			(layer "B.Fab")
		)
		(fp_line
			(start 0.12065 0.2794)
			(end 0.12065 0.3048)
			(stroke
				(width 0.1)
				(type default)
			)
			(layer "B.Fab")
		)
		(fp_line
			(start 0.12065 0.3048)
			(end 0.67945 0.3048)
			(stroke
				(width 0.1)
				(type default)
			)
			(layer "B.Fab")
		)
		(fp_line
			(start 0.67945 -0.305054)
			(end 0.12065 -0.305054)
			(stroke
				(width 0.1)
				(type default)
			)
			(layer "B.Fab")
		)
		(fp_line
			(start 0.67945 0.3048)
			(end 0.67945 -0.305054)
			(stroke
				(width 0.1)
				(type default)
			)
			(layer "B.Fab")
		)
		(pad "1" smd circle
			(at 0.40005 0 180)
			(size 0 0)
			(layers "B.Cu" "B.Mask" "B.Paste")
			(net "P3V3_PEX_USB_HUB")
		)
		(pad "2" smd circle
			(at -0.40005 0 180)
			(size 0 0)
			(layers "B.Cu" "B.Mask" "B.Paste")
			(net "GND")
		)
	)
	(footprint ""
		(layer "B.Cu")
		(at 394.164312 -145.284952 180)
		(property "Reference" "C941"
			(at 0 0 0)
			(layer "B.SilkS")
			(hide yes)
			(effects
				(font
					(size 1.27 1.27)
				)
				(justify mirror)
			)
		)
		(property "Value" ""
			(at 0 0 0)
			(layer "B.Fab")
			(effects
				(font
					(size 1.27 1.27)
				)
				(justify mirror)
			)
		)
		(duplicate_pad_numbers_are_jumpers no)
		(fp_line
			(start 0.299974 0.150114)
			(end 0.299974 -0.150114)
			(stroke
				(width 0.1)
				(type default)
			)
			(layer "B.Fab")
		)
		(fp_line
			(start 0.299974 -0.150114)
			(end -0.299974 -0.150114)
			(stroke
				(width 0.1)
				(type default)
			)
			(layer "B.Fab")
		)
		(fp_line
			(start -0.299974 0.150114)
			(end 0.299974 0.150114)
			(stroke
				(width 0.1)
				(type default)
			)
			(layer "B.Fab")
		)
		(fp_line
			(start -0.299974 -0.150114)
			(end -0.299974 0.150114)
			(stroke
				(width 0.1)
				(type default)
			)
			(layer "B.Fab")
		)
		(pad "1" smd rect
			(at 0.2667 0)
			(size 0.3048 0.381)
			(layers "B.Cu" "B.Mask" "B.Paste")
			(net "P12V_NIC6")
		)
		(pad "2" smd rect
			(at -0.2667 0)
			(size 0.3048 0.381)
			(layers "B.Cu" "B.Mask" "B.Paste")
			(net "GND")
		)
	)
	(footprint ""
		(layer "B.Cu")
		(at 419.58641 -117.66169)
		(property "Reference" "R360"
			(at 0 0 0)
			(layer "B.SilkS")
			(hide yes)
			(effects
				(font
					(size 1.27 1.27)
				)
				(justify mirror)
			)
		)
		(property "Value" ""
			(at 0 0 0)
			(layer "B.Fab")
			(effects
				(font
					(size 1.27 1.27)
				)
				(justify mirror)
			)
		)
		(duplicate_pad_numbers_are_jumpers no)
		(fp_line
			(start -0.7874 -0.4064)
			(end -0.7874 0.4064)
			(stroke
				(width 0.1524)
				(type default)
			)
			(layer "B.SilkS")
		)
		(fp_line
			(start -0.7874 0.4064)
			(end 0.7874 0.4064)
			(stroke
				(width 0.1524)
				(type default)
			)
			(layer "B.SilkS")
		)
		(fp_line
			(start 0.7874 -0.4064)
			(end -0.7874 -0.4064)
			(stroke
				(width 0.1524)
				(type default)
			)
			(layer "B.SilkS")
		)
		(fp_line
			(start 0.7874 0.4064)
			(end 0.7874 -0.4064)
			(stroke
				(width 0.1524)
				(type default)
			)
			(layer "B.SilkS")
		)
		(fp_line
			(start -0.67945 -0.3048)
			(end -0.67945 0.3048)
			(stroke
				(width 0.1)
				(type default)
			)
			(layer "B.Fab")
		)
		(fp_line
			(start -0.67945 0.3048)
			(end -0.120396 0.3048)
			(stroke
				(width 0.1)
				(type default)
			)
			(layer "B.Fab")
		)
		(fp_line
			(start -0.12065 -0.3048)
			(end -0.67945 -0.3048)
			(stroke
				(width 0.1)
				(type default)
			)
			(layer "B.Fab")
		)
		(fp_line
			(start -0.12065 -0.2794)
			(end -0.12065 -0.3048)
			(stroke
				(width 0.1)
				(type default)
			)
			(layer "B.Fab")
		)
		(fp_line
			(start -0.120396 0.2794)
			(end 0.12065 0.2794)
			(stroke
				(width 0.1)
				(type default)
			)
			(layer "B.Fab")
		)
		(fp_line
			(start -0.120396 0.3048)
			(end -0.120396 0.2794)
			(stroke
				(width 0.1)
				(type default)
			)
			(layer "B.Fab")
		)
		(fp_line
			(start 0.12065 -0.305054)
			(end 0.12065 -0.2794)
			(stroke
				(width 0.1)
				(type default)
			)
			(layer "B.Fab")
		)
		(fp_line
			(start 0.12065 -0.2794)
			(end -0.12065 -0.2794)
			(stroke
				(width 0.1)
				(type default)
			)
			(layer "B.Fab")
		)
		(fp_line
			(start 0.12065 0.2794)
			(end 0.12065 0.3048)
			(stroke
				(width 0.1)
				(type default)
			)
			(layer "B.Fab")
		)
		(fp_line
			(start 0.12065 0.3048)
			(end 0.67945 0.3048)
			(stroke
				(width 0.1)
				(type default)
			)
			(layer "B.Fab")
		)
		(fp_line
			(start 0.67945 -0.305054)
			(end 0.12065 -0.305054)
			(stroke
				(width 0.1)
				(type default)
			)
			(layer "B.Fab")
		)
		(fp_line
			(start 0.67945 0.3048)
			(end 0.67945 -0.305054)
			(stroke
				(width 0.1)
				(type default)
			)
			(layer "B.Fab")
		)
		(pad "1" smd circle
			(at 0.40005 0 180)
			(size 0 0)
			(layers "B.Cu" "B.Mask" "B.Paste")
			(net "NIC7_AUX_PWR_EN_R")
		)
		(pad "2" smd circle
			(at -0.40005 0 180)
			(size 0 0)
			(layers "B.Cu" "B.Mask" "B.Paste")
			(net "NIC7_AUX_PWR_EN")
		)
	)
)
